(kicad_pcb
	(version 20221018)
	(generator pcbnew)
	(general
    (thickness 1.7403)
  )
	(paper "A4")
	(title_block
    (title "Data Center RDIMM DDR4 Tester")
    (date "2024-09-30")
    (rev "1.2.4")
		(comment 9 "footprints 558-563 of 690")
	)
	(layers
    (0 "F.Cu" signal)
    (1 "In1.Cu" power)
    (2 "In2.Cu" signal)
    (3 "In3.Cu" power)
    (4 "In4.Cu" power)
    (5 "In5.Cu" signal)
    (6 "In6.Cu" power)
    (7 "In7.Cu" signal)
    (8 "In8.Cu" power)
    (9 "In9.Cu" signal)
    (10 "In10.Cu" power)
    (31 "B.Cu" signal)
    (32 "B.Adhes" user "B.Adhesive")
    (33 "F.Adhes" user "F.Adhesive")
    (34 "B.Paste" user)
    (35 "F.Paste" user)
    (36 "B.SilkS" user "B.Silkscreen")
    (37 "F.SilkS" user "F.Silkscreen")
    (38 "B.Mask" user)
    (39 "F.Mask" user)
    (40 "Dwgs.User" user "User.Drawings")
    (41 "Cmts.User" user "User.Comments")
    (42 "Eco1.User" user "User.Eco1")
    (43 "Eco2.User" user "User.Eco2")
    (44 "Edge.Cuts" user)
    (45 "Margin" user)
    (46 "B.CrtYd" user "B.Courtyard")
    (47 "F.CrtYd" user "F.Courtyard")
    (48 "B.Fab" user)
    (49 "F.Fab" user)
  )
	(footprint "data-center-rdimm-ddr4-tester-footprints:R_0402_1005Metric" (layer "B.Cu")
    (at 241.4 80.4 180)
    (descr "Resistor SMD 0402")
    (tags "resistor SMD 0402")
    (property "Author" "Antmicro")
    (property "License" "Apache-2.0")
    (property "MPN" "CR0402-FX-3300GLF")
    (property "Manufacturer" "Bourns")
    (property "Sheetfile" "interfaces.kicad_sch")
    (property "Sheetname" "Interfaces")
    (property "Tolerance" "1%")
    (property "Val" "330R")
    (property "ki_description" "330R resistor in 0402 package with 1% tolerance")
    (attr smd)
    (fp_text reference "R188" (at -1.67 -1.31) (layer "B.SilkS")
        (effects (font (size 0.7 0.7) (thickness 0.15)) (justify left bottom mirror))
    )
    (fp_text value "R_330R_0402" (at 0 -1.4) (layer "B.Fab") hide
        (effects (font (size 0.7 0.7) (thickness 0.15)) (justify left bottom mirror))
    )
    (fp_text user "${REFERENCE}" (at -0.95 -3.168) (layer "B.Fab") hide
        (effects (font (size 0.7 0.7) (thickness 0.15)) (justify left bottom mirror))
    )
    (fp_text user "License: Apache-2.0" (at -0.95 -5.169) (layer "B.Fab") hide
        (effects (font (size 0.7 0.7) (thickness 0.15)) (justify left bottom mirror))
    )
    (fp_text user "Author: Antmicro" (at -0.95 -4.169) (layer "B.Fab") hide
        (effects (font (size 0.7 0.7) (thickness 0.15)) (justify left bottom mirror))
    )
    (fp_rect (start -0.93 0.47) (end 0.93 -0.47)
      (stroke (width 0.05) (type solid)) (fill none) (layer "B.CrtYd"))
    (fp_rect (start -0.5 0.25) (end 0.5 -0.25)
      (stroke (width 0.15) (type solid)) (fill none) (layer "B.Fab"))
    (pad "1" smd roundrect (at -0.485 0 180) (size 0.59 0.64) (layers "B.Cu" "B.Paste" "B.Mask") (roundrect_rratio 0.25)
      (net 102 "Net-(D17-C_{G})") (pintype "passive"))
    (pad "2" smd roundrect (at 0.485 0 180) (size 0.59 0.64) (layers "B.Cu" "B.Paste" "B.Mask") (roundrect_rratio 0.25)
      (net 581 "Net-(Q9-D)") (pintype "passive"))
  )
	(footprint "data-center-rdimm-ddr4-tester-footprints:C_0402_1005Metric" (layer "B.Cu")
    (at 138.5 82.25 180)
    (descr "Capacitor SMD 0402")
    (tags "capacitor SMD 0402")
    (property "Author" "Antmicro")
    (property "Dielectric" "X5R")
    (property "License" "Apache-2.0")
    (property "MPN" "GRM155R61H104KE14D")
    (property "Manufacturer" "Murata")
    (property "Sheetfile" "supply.kicad_sch")
    (property "Sheetname" "Supply")
    (property "Val" "100n")
    (property "Voltage" "50V")
    (property "ki_description" " ")
    (attr smd)
    (fp_text reference "C284" (at -3.7 -0.42) (layer "B.SilkS")
        (effects (font (size 0.7 0.7) (thickness 0.15)) (justify left bottom mirror))
    )
    (fp_text value "C_100n_0402" (at 0 -1.4) (layer "B.Fab") hide
        (effects (font (size 0.7 0.7) (thickness 0.15)) (justify left bottom mirror))
    )
    (fp_text user "${REFERENCE}" (at -0.932 -3.168) (layer "B.Fab") hide
        (effects (font (size 0.7 0.7) (thickness 0.15)) (justify left bottom mirror))
    )
    (fp_text user "License: Apache-2.0" (at -0.932 -5.17) (layer "B.Fab") hide
        (effects (font (size 0.7 0.7) (thickness 0.15)) (justify left bottom mirror))
    )
    (fp_text user "Author: Antmicro" (at -0.932 -4.17) (layer "B.Fab") hide
        (effects (font (size 0.7 0.7) (thickness 0.15)) (justify left bottom mirror))
    )
    (fp_rect (start -0.94 0.47) (end 0.94 -0.47)
      (stroke (width 0.05) (type solid)) (fill none) (layer "B.CrtYd"))
    (fp_rect (start -0.499 0.249) (end 0.499 -0.249)
      (stroke (width 0.15) (type solid)) (fill none) (layer "B.Fab"))
    (pad "1" smd roundrect (at -0.484 0 180) (size 0.59 0.64) (layers "B.Cu" "B.Paste" "B.Mask") (roundrect_rratio 0.25)
      (net 307 "5V0_SYS") (pintype "passive"))
    (pad "2" smd roundrect (at 0.484 0 180) (size 0.59 0.64) (layers "B.Cu" "B.Paste" "B.Mask") (roundrect_rratio 0.25)
      (net 9 "GND") (pintype "passive"))
  )
	(footprint "data-center-rdimm-ddr4-tester-footprints:C_0402_1005Metric" (layer "B.Cu")
    (at 194.125 102.775 180)
    (descr "Capacitor SMD 0402")
    (tags "capacitor SMD 0402")
    (property "Author" "Antmicro")
    (property "Dielectric" "")
    (property "License" "Apache-2.0")
    (property "MPN" "GRM155R61A475MEAAD")
    (property "Manufacturer" "Murata")
    (property "Sheetfile" "fpga-power.kicad_sch")
    (property "Sheetname" "FPGA power")
    (property "Val" "4u7")
    (property "Voltage" "")
    (property "ki_description" " ")
    (attr smd)
    (fp_text reference "C256" (at -3.615 -0.345) (layer "B.SilkS")
        (effects (font (size 0.7 0.7) (thickness 0.15)) (justify left bottom mirror))
    )
    (fp_text value "C_4u7_0402" (at 0 -1.4) (layer "B.Fab") hide
        (effects (font (size 0.7 0.7) (thickness 0.15)) (justify left bottom mirror))
    )
    (fp_text user "${REFERENCE}" (at -0.932 -3.168) (layer "B.Fab") hide
        (effects (font (size 0.7 0.7) (thickness 0.15)) (justify left bottom mirror))
    )
    (fp_text user "Author: Antmicro" (at -0.932 -4.17) (layer "B.Fab") hide
        (effects (font (size 0.7 0.7) (thickness 0.15)) (justify left bottom mirror))
    )
    (fp_text user "License: Apache-2.0" (at -0.932 -5.17) (layer "B.Fab") hide
        (effects (font (size 0.7 0.7) (thickness 0.15)) (justify left bottom mirror))
    )
    (fp_rect (start -0.94 0.47) (end 0.94 -0.47)
      (stroke (width 0.05) (type solid)) (fill none) (layer "B.CrtYd"))
    (fp_rect (start -0.499 0.249) (end 0.499 -0.249)
      (stroke (width 0.15) (type solid)) (fill none) (layer "B.Fab"))
    (pad "1" smd roundrect (at -0.484 0 180) (size 0.59 0.64) (layers "B.Cu" "B.Paste" "B.Mask") (roundrect_rratio 0.25)
      (net 306 "1V2_SYS") (pintype "passive"))
    (pad "2" smd roundrect (at 0.484 0 180) (size 0.59 0.64) (layers "B.Cu" "B.Paste" "B.Mask") (roundrect_rratio 0.25)
      (net 9 "GND") (pintype "passive"))
  )
	(footprint "data-center-rdimm-ddr4-tester-footprints:PowerDI5" (layer "B.Cu")
    (at 182.15 112.85 180)
    (property "Author" "Antmicro")
    (property "License" "Apache-2.0")
    (property "MPN" "PDS760-13")
    (property "Manufacturer" "Diodes Incorporated")
    (property "Sheetfile" "ethernet.kicad_sch")
    (property "Sheetname" "Ethernet")
    (property "ki_description" "PDS760 Series 60 V 7 A Surface Mount Schottky Barrier Rectifier - PowerDI-5")
    (property "ki_keywords" "PDS760 Series 60 V 7 A Surface Mount Schottky Barrier Rectifier - PowerDI-5")
    (attr smd)
    (fp_text reference "D16" (at 0 2.55) (layer "B.SilkS")
        (effects (font (size 0.7 0.7) (thickness 0.15)) (justify left bottom mirror))
    )
    (fp_text value "PDS760" (at 0 -3.4) (layer "B.Fab") hide
        (effects (font (size 0.7 0.7) (thickness 0.15)) (justify right bottom mirror))
    )
    (fp_text user "Author: Antmicro" (at -3.302 -19.728) (layer "B.Fab") hide
        (effects (font (size 0.7 0.7) (thickness 0.15)) (justify left bottom mirror))
    )
    (fp_text user "${REFERENCE}" (at -3.302 -18.527) (layer "B.Fab") hide
        (effects (font (size 0.7 0.7) (thickness 0.15)) (justify left bottom mirror))
    )
    (fp_text user "License: Apache-2.0" (at -3.302 -20.928) (layer "B.Fab") hide
        (effects (font (size 0.7 0.7) (thickness 0.15)) (justify left bottom mirror))
    )
    (fp_line (start -2.7 -2.023) (end -2.7 -1.823)
      (stroke (width 0.12) (type solid)) (layer "B.SilkS"))
    (fp_line (start -2.7 1.8) (end -2.7 2)
      (stroke (width 0.12) (type solid)) (layer "B.SilkS"))
    (fp_line (start -2.7 2) (end 2.7 2)
      (stroke (width 0.12) (type solid)) (layer "B.SilkS"))
    (fp_line (start 2.7 -2.023) (end -2.7 -2.023)
      (stroke (width 0.12) (type solid)) (layer "B.SilkS"))
    (fp_line (start 2.7 -1.823) (end 2.7 -2.023)
      (stroke (width 0.12) (type solid)) (layer "B.SilkS"))
    (fp_line (start 2.7 2) (end 2.7 1.8)
      (stroke (width 0.12) (type solid)) (layer "B.SilkS"))
    (fp_rect (start -3.702 2.3) (end 3.7 -2.3)
      (stroke (width 0.05) (type solid)) (fill none) (layer "B.CrtYd"))
    (pad "A" smd roundrect (at -2.862 -0.941 270) (size 1.39 1.4) (layers "B.Cu" "B.Paste" "B.Mask") (roundrect_rratio 0.25)
      (net 864 "VIN_POE") (pinfunction "A") (pintype "passive"))
    (pad "A" smd roundrect (at -2.862 0.94 90) (size 1.39 1.4) (layers "B.Cu" "B.Paste" "B.Mask") (roundrect_rratio 0.25)
      (net 864 "VIN_POE") (pinfunction "A") (pintype "passive"))
    (pad "C" smd roundrect (at 1.1 0 270) (size 3.36 4.86) (layers "B.Cu" "B.Paste" "B.Mask") (roundrect_rratio 0.05)
      (net 103 "VIN") (pinfunction "C") (pintype "passive"))
  )
	(footprint "data-center-rdimm-ddr4-tester-footprints:R_0603_1608Metric" (layer "B.Cu")
    (at 158.75 132.775 180)
    (descr "Resistor SMD 0603")
    (tags "resistor SMD 0603")
    (property "Author" "Antmicro")
    (property "License" "Apache-2.0")
    (property "MPN" "CR0603-FX-1001ELF")
    (property "Manufacturer" "Bourns")
    (property "Sheetfile" "ethernet.kicad_sch")
    (property "Sheetname" "Ethernet")
    (property "Tolerance" "1%")
    (property "Val" "1k")
    (property "ki_description" "1k resistor in 0603 package with 1% tolerance")
    (attr smd)
    (fp_text reference "R184" (at -0.74 -1.305) (layer "B.SilkS")
        (effects (font (size 0.7 0.7) (thickness 0.15)) (justify left bottom mirror))
    )
    (fp_text value "R_1k_0603" (at 0 -1.6) (layer "B.Fab") hide
        (effects (font (size 0.7 0.7) (thickness 0.15)) (justify left bottom mirror))
    )
    (fp_text user "${REFERENCE}" (at -1.25 -3.898) (layer "B.Fab") hide
        (effects (font (size 0.7 0.7) (thickness 0.15)) (justify left bottom mirror))
    )
    (fp_text user "License: Apache-2.0" (at -1.25 -5.9) (layer "B.Fab") hide
        (effects (font (size 0.7 0.7) (thickness 0.15)) (justify left bottom mirror))
    )
    (fp_text user "Author: Antmicro" (at -1.25 -4.9) (layer "B.Fab") hide
        (effects (font (size 0.7 0.7) (thickness 0.15)) (justify left bottom mirror))
    )
    (fp_line (start -0.3 -0.3) (end 0.3 -0.3)
      (stroke (width 0.15) (type solid)) (layer "B.SilkS"))
    (fp_line (start -0.3 0.3) (end 0.3 0.3)
      (stroke (width 0.15) (type solid)) (layer "B.SilkS"))
    (fp_rect (start -1.25 0.7) (end 1.25 -0.7)
      (stroke (width 0.05) (type solid)) (fill none) (layer "B.CrtYd"))
    (fp_rect (start -0.8 0.4) (end 0.8 -0.4)
      (stroke (width 0.15) (type solid)) (fill none) (layer "B.Fab"))
    (pad "1" smd roundrect (at -0.7 0 180) (size 0.6 0.8) (layers "B.Cu" "B.Paste" "B.Mask") (roundrect_rratio 0.2)
      (net 628 "Net-(IC2-Pad2)") (pintype "passive"))
    (pad "2" smd roundrect (at 0.7 0 180) (size 0.6 0.8) (layers "B.Cu" "B.Paste" "B.Mask") (roundrect_rratio 0.2)
      (net 9 "GND") (pintype "passive"))
  )
	(footprint "data-center-rdimm-ddr4-tester-footprints:SOT-143-4" (layer "B.Cu")
    (at 130.075 108.86 90)
    (descr "http://datasheets.maximintegrated.com/en/ds/MAX6816-MAX6818.pdf")
    (property "Author" "Antmicro")
    (property "License" "Apache-2.0")
    (property "MPN" "MAX812REUS+T")
    (property "Manufacturer" "Maxim Integrated")
    (property "Sheetfile" "supply.kicad_sch")
    (property "Sheetname" "Supply")
    (property "ki_description" "Supervisory Circuits 4-Pin uP Voltage Monitors with Manual Reset Input")
    (attr smd)
    (fp_text reference "U18" (at -1.31 1.855 270) (layer "B.SilkS")
        (effects (font (size 0.7 0.7) (thickness 0.15)) (justify left bottom mirror))
    )
    (fp_text value "MAX812REUS+T" (at 0 -2.999 270) (layer "B.Fab") hide
        (effects (font (size 0.7 0.7) (thickness 0.15)) (justify left bottom mirror))
    )
    (fp_text user "License: Apache-2.0" (at -1.601 -7.4 270) (layer "B.Fab") hide
        (effects (font (size 0.7 0.7) (thickness 0.15)) (justify left bottom mirror))
    )
    (fp_text user "${REFERENCE}" (at -1.601 -4.998 270) (layer "B.Fab") hide
        (effects (font (size 0.7 0.7) (thickness 0.15)) (justify left bottom mirror))
    )
    (fp_text user "Author: Antmicro" (at -1.601 -6.2 270) (layer "B.Fab") hide
        (effects (font (size 0.7 0.7) (thickness 0.15)) (justify left bottom mirror))
    )
    (fp_line (start -1.601 0.802) (end -1.601 -1.7)
      (stroke (width 0.15) (type solid)) (layer "B.SilkS"))
    (fp_line (start 1.6 0.802) (end 1.6 -0.8)
      (stroke (width 0.15) (type solid)) (layer "B.SilkS"))
    (fp_circle (center -2.1 -1.7) (end -2.05 -1.7)
      (stroke (width 0.15) (type solid)) (fill solid) (layer "B.SilkS"))
    (fp_rect (start -1.776 1.896) (end 1.773 -1.895)
      (stroke (width 0.05) (type solid)) (fill none) (layer "B.CrtYd"))
    (fp_line (start -1.46 -0.65) (end -1.46 0.652)
      (stroke (width 0.15) (type solid)) (layer "B.Fab"))
    (fp_line (start -1.46 -0.65) (end 1.459 -0.65)
      (stroke (width 0.15) (type solid)) (layer "B.Fab"))
    (fp_line (start 1.459 0.652) (end -1.46 0.652)
      (stroke (width 0.15) (type solid)) (layer "B.Fab"))
    (fp_line (start 1.459 0.652) (end 1.459 -0.65)
      (stroke (width 0.15) (type solid)) (layer "B.Fab"))
    (pad "1" smd roundrect (at -0.76 -0.998 90) (size 0.94 1.31) (layers "B.Cu" "B.Paste" "B.Mask") (roundrect_rratio 0.25)
      (net 9 "GND") (pinfunction "GND") (pintype "power_in"))
    (pad "2" smd roundrect (at 0.959 -0.998 90) (size 0.55 1.31) (layers "B.Cu" "B.Paste" "B.Mask") (roundrect_rratio 0.25)
      (net 798 "/Supply/FPGA_PWR_DIS") (pinfunction "~{RST}") (pintype "output"))
    (pad "3" smd roundrect (at 0.959 1 90) (size 0.55 1.31) (layers "B.Cu" "B.Paste" "B.Mask") (roundrect_rratio 0.25)
      (net 583 "Net-(Q11-D)") (pinfunction "~{MR}") (pintype "input"))
    (pad "4" smd roundrect (at -0.96 1 90) (size 0.55 1.31) (layers "B.Cu" "B.Paste" "B.Mask") (roundrect_rratio 0.25)
      (net 307 "5V0_SYS") (pinfunction "VCC") (pintype "power_in"))
  )
)
